(kicad_pcb
	(version 20241229)
	(generator "pcbnew")
	(generator_version "9.0")
	(general
		(thickness 1.63)
		(legacy_teardrops no)
	)
	(paper "A4")
	(title_block
		(title "CM4 Baseboard")
		(date "2026-01-05")
		(rev "1.1.1")
		(company "Antmicro Ltd")
		(comment 1 "www.antmicro.com")
		(comment 9 "footprints 394-398 of 506")
	)
	(layers
		(0 "F.Cu" signal)
		(4 "In1.Cu" power)
		(6 "In2.Cu" power)
		(8 "In3.Cu" signal)
		(10 "In4.Cu" signal)
		(2 "B.Cu" signal)
		(9 "F.Adhes" user "F.Adhesive")
		(11 "B.Adhes" user "B.Adhesive")
		(13 "F.Paste" user)
		(15 "B.Paste" user)
		(5 "F.SilkS" user "F.Silkscreen")
		(7 "B.SilkS" user "B.Silkscreen")
		(1 "F.Mask" user)
		(3 "B.Mask" user)
		(17 "Dwgs.User" user "User.Drawings")
		(19 "Cmts.User" user "User.Comments")
		(21 "Eco1.User" user "User.Eco1")
		(23 "Eco2.User" user "User.Eco2")
		(25 "Edge.Cuts" user)
		(27 "Margin" user)
		(31 "F.CrtYd" user "F.Courtyard")
		(29 "B.CrtYd" user "B.Courtyard")
		(35 "F.Fab" user)
		(33 "B.Fab" user)
	)
	(footprint "antmicro-footprints:R_0402_1005Metric"
		(layer "B.Cu")
		(at 75.342962 136.0165)
		(descr "Resistor SMD 0402")
		(tags "resistor SMD 0402")
		(property "Reference" "R917"
			(at -3.835 0.38 0)
			(layer "B.SilkS")
			(effects
				(font
					(size 0.7 0.7)
					(thickness 0.15)
				)
				(justify right bottom mirror)
			)
		)
		(property "Value" "R_15k_0402"
			(at -1.011843 -1.772047 0)
			(layer "B.Fab")
			(effects
				(font
					(size 0.7 0.7)
					(thickness 0.15)
				)
				(justify right bottom mirror)
			)
		)
		(property "Datasheet" "https://www.bourns.com/docs/product-datasheets/cr.pdf"
			(at 0 0 0)
			(layer "B.Fab")
			(hide yes)
			(effects
				(font
					(size 1.27 1.27)
					(thickness 0.15)
				)
			)
		)
		(property "Manufacturer" "Bourns"
			(at 0 0 0)
			(unlocked yes)
			(layer "B.Fab")
			(hide yes)
			(effects
				(font
					(size 1 1)
					(thickness 0.15)
				)
				(justify mirror)
			)
		)
		(property "MPN" "CR0402-FX-1502GLF"
			(at 0 0 0)
			(unlocked yes)
			(layer "B.Fab")
			(hide yes)
			(effects
				(font
					(size 1 1)
					(thickness 0.15)
				)
				(justify mirror)
			)
		)
		(property "Val" "15k"
			(at 0 0 0)
			(unlocked yes)
			(layer "B.Fab")
			(hide yes)
			(effects
				(font
					(size 1 1)
					(thickness 0.15)
				)
				(justify mirror)
			)
		)
		(property "License" "Apache-2.0"
			(at 0 0 0)
			(unlocked yes)
			(layer "B.Fab")
			(hide yes)
			(effects
				(font
					(size 1 1)
					(thickness 0.15)
				)
				(justify mirror)
			)
		)
		(property "Author" "Antmicro"
			(at 0 0 0)
			(unlocked yes)
			(layer "B.Fab")
			(hide yes)
			(effects
				(font
					(size 1 1)
					(thickness 0.15)
				)
				(justify mirror)
			)
		)
		(property "Tolerance" "1%"
			(at 0 0 0)
			(unlocked yes)
			(layer "B.Fab")
			(hide yes)
			(effects
				(font
					(size 1 1)
					(thickness 0.15)
				)
				(justify mirror)
			)
		)
		(sheetname "/USB/")
		(sheetfile "usb.kicad_sch")
		(attr smd)
		(fp_rect
			(start -0.925 0.47)
			(end 0.925 -0.47)
			(stroke
				(width 0.05)
				(type default)
			)
			(fill no)
			(layer "B.CrtYd")
		)
		(fp_rect
			(start -0.5 0.25)
			(end 0.5 -0.25)
			(stroke
				(width 0.15)
				(type solid)
			)
			(fill no)
			(layer "B.Fab")
		)
		(fp_text user "${REFERENCE}"
			(at -0.95 -3.168 180)
			(layer "B.Fab")
			(effects
				(font
					(size 0.7 0.7)
					(thickness 0.15)
				)
				(justify left bottom mirror)
			)
		)
		(fp_text user "Author: Antmicro"
			(at -0.95 -4.169 180)
			(layer "B.Fab")
			(effects
				(font
					(size 0.7 0.7)
					(thickness 0.15)
				)
				(justify left bottom mirror)
			)
		)
		(fp_text user "License: Apache-2.0"
			(at -0.95 -5.169 180)
			(layer "B.Fab")
			(effects
				(font
					(size 0.7 0.7)
					(thickness 0.15)
				)
				(justify left bottom mirror)
			)
		)
		(pad "1" smd roundrect
			(at -0.48 0)
			(size 0.59 0.64)
			(layers "B.Cu" "B.Mask" "B.Paste")
			(roundrect_rratio 0.25)
			(net 3 "GND")
			(pintype "passive")
		)
		(pad "2" smd roundrect
			(at 0.48 0)
			(size 0.59 0.64)
			(layers "B.Cu" "B.Mask" "B.Paste")
			(roundrect_rratio 0.25)
			(net 29 "/USB/USBD_SVBUS")
			(pintype "passive")
		)
	)
	(footprint "antmicro-footprints:R_0603_1608Metric"
		(layer "B.Cu")
		(at 69.917962 159.1665)
		(descr "Resistor SMD 0603")
		(tags "resistor SMD 0603")
		(property "Reference" "R324"
			(at 1.29 0.37 0)
			(layer "B.SilkS")
			(effects
				(font
					(size 0.7 0.7)
					(thickness 0.15)
				)
				(justify right bottom mirror)
			)
		)
		(property "Value" "R_0R_22.4A_0603"
			(at 0 -1.6 0)
			(layer "B.Fab")
			(effects
				(font
					(size 0.7 0.7)
					(thickness 0.15)
				)
				(justify right bottom mirror)
			)
		)
		(property "Datasheet" "https://fscdn.rohm.com/en/products/databook/datasheet/passive/resistor/chip_resistor/pmr-jpw-e.pdf"
			(at 0 0 0)
			(layer "B.Fab")
			(hide yes)
			(effects
				(font
					(size 1.27 1.27)
					(thickness 0.15)
				)
			)
		)
		(property "Manufacturer" "ROHM Semiconductor"
			(at 0 0 0)
			(unlocked yes)
			(layer "B.Fab")
			(hide yes)
			(effects
				(font
					(size 1 1)
					(thickness 0.15)
				)
				(justify mirror)
			)
		)
		(property "MPN" "PMR03EZPJ000"
			(at 0 0 0)
			(unlocked yes)
			(layer "B.Fab")
			(hide yes)
			(effects
				(font
					(size 1 1)
					(thickness 0.15)
				)
				(justify mirror)
			)
		)
		(property "Val" "0R"
			(at 0 0 0)
			(unlocked yes)
			(layer "B.Fab")
			(hide yes)
			(effects
				(font
					(size 1 1)
					(thickness 0.15)
				)
				(justify mirror)
			)
		)
		(property "Author" "Antmicro"
			(at 0 0 0)
			(unlocked yes)
			(layer "B.Fab")
			(hide yes)
			(effects
				(font
					(size 1 1)
					(thickness 0.15)
				)
				(justify mirror)
			)
		)
		(property "License" "Apache-2.0"
			(at 0 0 0)
			(unlocked yes)
			(layer "B.Fab")
			(hide yes)
			(effects
				(font
					(size 1 1)
					(thickness 0.15)
				)
				(justify mirror)
			)
		)
		(property "Max. Curr." "22.4A"
			(at 0 0 0)
			(unlocked yes)
			(layer "B.Fab")
			(hide yes)
			(effects
				(font
					(size 1 1)
					(thickness 0.15)
				)
				(justify mirror)
			)
		)
		(property "Tolerance" "template_tolerance"
			(at 0 0 0)
			(unlocked yes)
			(layer "B.Fab")
			(hide yes)
			(effects
				(font
					(size 1 1)
					(thickness 0.15)
				)
				(justify mirror)
			)
		)
		(sheetname "/Supply/")
		(sheetfile "supply.kicad_sch")
		(attr smd)
		(fp_line
			(start -0.15 -0.4)
			(end 0.15 -0.4)
			(stroke
				(width 0.15)
				(type solid)
			)
			(layer "B.SilkS")
		)
		(fp_line
			(start -0.15 0.4)
			(end 0.15 0.4)
			(stroke
				(width 0.15)
				(type solid)
			)
			(layer "B.SilkS")
		)
		(fp_rect
			(start -1.25 0.65)
			(end 1.25 -0.65)
			(stroke
				(width 0.05)
				(type solid)
			)
			(fill no)
			(layer "B.CrtYd")
		)
		(fp_rect
			(start -0.8 0.4)
			(end 0.8 -0.4)
			(stroke
				(width 0.15)
				(type solid)
			)
			(fill no)
			(layer "B.Fab")
		)
		(fp_text user "Author: Antmicro"
			(at -1.25 -4.9 180)
			(layer "B.Fab")
			(effects
				(font
					(size 0.7 0.7)
					(thickness 0.15)
				)
				(justify left bottom mirror)
			)
		)
		(fp_text user "License: Apache-2.0"
			(at -1.25 -5.9 180)
			(layer "B.Fab")
			(effects
				(font
					(size 0.7 0.7)
					(thickness 0.15)
				)
				(justify left bottom mirror)
			)
		)
		(fp_text user "${REFERENCE}"
			(at -1.25 -3.898 180)
			(layer "B.Fab")
			(effects
				(font
					(size 0.7 0.7)
					(thickness 0.15)
				)
				(justify left bottom mirror)
			)
		)
		(pad "1" smd roundrect
			(at -0.7 0)
			(size 0.8 1)
			(layers "B.Cu" "B.Mask" "B.Paste")
			(roundrect_rratio 0.2)
			(net 77 "/Supply/OUT_5V")
			(pintype "passive")
		)
		(pad "2" smd roundrect
			(at 0.7 0)
			(size 0.8 1)
			(layers "B.Cu" "B.Mask" "B.Paste")
			(roundrect_rratio 0.2)
			(net 10 "+5V")
			(pintype "passive")
		)
	)
	(footprint "antmicro-footprints:R_0402_1005Metric"
		(layer "B.Cu")
		(at 118.892962 118.1415 90)
		(descr "Resistor SMD 0402")
		(tags "resistor SMD 0402")
		(property "Reference" "R502"
			(at -2.025 -0.585 90)
			(layer "B.SilkS")
			(effects
				(font
					(size 0.7 0.7)
					(thickness 0.15)
				)
				(justify right bottom mirror)
			)
		)
		(property "Value" "R_10k_0402"
			(at -1.011843 -1.772047 90)
			(layer "B.Fab")
			(effects
				(font
					(size 0.7 0.7)
					(thickness 0.15)
				)
				(justify right bottom mirror)
			)
		)
		(property "Datasheet" "https://www.bourns.com/docs/product-datasheets/cr.pdf"
			(at 0 0 90)
			(layer "B.Fab")
			(hide yes)
			(effects
				(font
					(size 1.27 1.27)
					(thickness 0.15)
				)
			)
		)
		(property "Manufacturer" "Bourns"
			(at 0 0 90)
			(unlocked yes)
			(layer "B.Fab")
			(hide yes)
			(effects
				(font
					(size 1 1)
					(thickness 0.15)
				)
				(justify mirror)
			)
		)
		(property "MPN" "CR0402-FX-1002GLF"
			(at 0 0 90)
			(unlocked yes)
			(layer "B.Fab")
			(hide yes)
			(effects
				(font
					(size 1 1)
					(thickness 0.15)
				)
				(justify mirror)
			)
		)
		(property "Val" "10k"
			(at 0 0 90)
			(unlocked yes)
			(layer "B.Fab")
			(hide yes)
			(effects
				(font
					(size 1 1)
					(thickness 0.15)
				)
				(justify mirror)
			)
		)
		(property "License" "Apache-2.0"
			(at 0 0 90)
			(unlocked yes)
			(layer "B.Fab")
			(hide yes)
			(effects
				(font
					(size 1 1)
					(thickness 0.15)
				)
				(justify mirror)
			)
		)
		(property "Author" "Antmicro"
			(at 0 0 90)
			(unlocked yes)
			(layer "B.Fab")
			(hide yes)
			(effects
				(font
					(size 1 1)
					(thickness 0.15)
				)
				(justify mirror)
			)
		)
		(property "Tolerance" "1%"
			(at 0 0 90)
			(unlocked yes)
			(layer "B.Fab")
			(hide yes)
			(effects
				(font
					(size 1 1)
					(thickness 0.15)
				)
				(justify mirror)
			)
		)
		(sheetname "/NVMe & microSD/")
		(sheetfile "nvme-micro-sd.kicad_sch")
		(attr smd)
		(fp_rect
			(start -0.925 0.47)
			(end 0.925 -0.47)
			(stroke
				(width 0.05)
				(type default)
			)
			(fill no)
			(layer "B.CrtYd")
		)
		(fp_rect
			(start -0.5 0.25)
			(end 0.5 -0.25)
			(stroke
				(width 0.15)
				(type solid)
			)
			(fill no)
			(layer "B.Fab")
		)
		(fp_text user "Author: Antmicro"
			(at -0.95 -4.169 270)
			(layer "B.Fab")
			(effects
				(font
					(size 0.7 0.7)
					(thickness 0.15)
				)
				(justify left bottom mirror)
			)
		)
		(fp_text user "License: Apache-2.0"
			(at -0.95 -5.169 270)
			(layer "B.Fab")
			(effects
				(font
					(size 0.7 0.7)
					(thickness 0.15)
				)
				(justify left bottom mirror)
			)
		)
		(fp_text user "${REFERENCE}"
			(at -0.95 -3.168 270)
			(layer "B.Fab")
			(effects
				(font
					(size 0.7 0.7)
					(thickness 0.15)
				)
				(justify left bottom mirror)
			)
		)
		(pad "1" smd roundrect
			(at -0.48 0 90)
			(size 0.59 0.64)
			(layers "B.Cu" "B.Mask" "B.Paste")
			(roundrect_rratio 0.25)
			(net 144 "/Compute module/NVMe.~{CLK_REQ}")
			(pintype "passive")
		)
		(pad "2" smd roundrect
			(at 0.48 0 90)
			(size 0.59 0.64)
			(layers "B.Cu" "B.Mask" "B.Paste")
			(roundrect_rratio 0.25)
			(net 65 "3V3_SSD")
			(pintype "passive")
		)
	)
	(footprint "antmicro-footprints:R_0402_1005Metric"
		(layer "B.Cu")
		(at 126.4 169.05 180)
		(descr "Resistor SMD 0402")
		(tags "resistor SMD 0402")
		(property "Reference" "R505"
			(at 1.01 -0.435 0)
			(layer "B.SilkS")
			(effects
				(font
					(size 0.7 0.7)
					(thickness 0.15)
				)
				(justify left bottom mirror)
			)
		)
		(property "Value" "R_470R_0402"
			(at -1.011843 -1.772047 0)
			(layer "B.Fab")
			(effects
				(font
					(size 0.7 0.7)
					(thickness 0.15)
				)
				(justify left bottom mirror)
			)
		)
		(property "Datasheet" "https://www.bourns.com/docs/product-datasheets/cr.pdf"
			(at 0 0 180)
			(layer "B.Fab")
			(hide yes)
			(effects
				(font
					(size 1.27 1.27)
					(thickness 0.15)
				)
			)
		)
		(property "Manufacturer" "Bourns"
			(at 0 0 180)
			(unlocked yes)
			(layer "B.Fab")
			(hide yes)
			(effects
				(font
					(size 1 1)
					(thickness 0.15)
				)
				(justify mirror)
			)
		)
		(property "MPN" "CR0402-FX-4700GLF"
			(at 0 0 180)
			(unlocked yes)
			(layer "B.Fab")
			(hide yes)
			(effects
				(font
					(size 1 1)
					(thickness 0.15)
				)
				(justify mirror)
			)
		)
		(property "Val" "470R"
			(at 0 0 180)
			(unlocked yes)
			(layer "B.Fab")
			(hide yes)
			(effects
				(font
					(size 1 1)
					(thickness 0.15)
				)
				(justify mirror)
			)
		)
		(property "License" "Apache-2.0"
			(at 0 0 180)
			(unlocked yes)
			(layer "B.Fab")
			(hide yes)
			(effects
				(font
					(size 1 1)
					(thickness 0.15)
				)
				(justify mirror)
			)
		)
		(property "Author" "Antmicro"
			(at 0 0 180)
			(unlocked yes)
			(layer "B.Fab")
			(hide yes)
			(effects
				(font
					(size 1 1)
					(thickness 0.15)
				)
				(justify mirror)
			)
		)
		(property "Tolerance" "1%"
			(at 0 0 180)
			(unlocked yes)
			(layer "B.Fab")
			(hide yes)
			(effects
				(font
					(size 1 1)
					(thickness 0.15)
				)
				(justify mirror)
			)
		)
		(sheetname "/NVMe & microSD/")
		(sheetfile "nvme-micro-sd.kicad_sch")
		(attr smd)
		(fp_rect
			(start -0.925 0.47)
			(end 0.925 -0.47)
			(stroke
				(width 0.05)
				(type default)
			)
			(fill no)
			(layer "B.CrtYd")
		)
		(fp_rect
			(start -0.5 0.25)
			(end 0.5 -0.25)
			(stroke
				(width 0.15)
				(type solid)
			)
			(fill no)
			(layer "B.Fab")
		)
		(fp_text user "${REFERENCE}"
			(at -0.95 -3.168 0)
			(layer "B.Fab")
			(effects
				(font
					(size 0.7 0.7)
					(thickness 0.15)
				)
				(justify left bottom mirror)
			)
		)
		(fp_text user "License: Apache-2.0"
			(at -0.95 -5.169 0)
			(layer "B.Fab")
			(effects
				(font
					(size 0.7 0.7)
					(thickness 0.15)
				)
				(justify left bottom mirror)
			)
		)
		(fp_text user "Author: Antmicro"
			(at -0.95 -4.169 0)
			(layer "B.Fab")
			(effects
				(font
					(size 0.7 0.7)
					(thickness 0.15)
				)
				(justify left bottom mirror)
			)
		)
		(pad "1" smd roundrect
			(at -0.48 0 180)
			(size 0.59 0.64)
			(layers "B.Cu" "B.Mask" "B.Paste")
			(roundrect_rratio 0.25)
			(net 263 "Net-(J502-CD2)")
			(pintype "passive")
		)
		(pad "2" smd roundrect
			(at 0.48 0 180)
			(size 0.59 0.64)
			(layers "B.Cu" "B.Mask" "B.Paste")
			(roundrect_rratio 0.25)
			(net 118 "/Compute module/SDIO.CD")
			(pintype "passive")
		)
	)
	(footprint "antmicro-footprints:R_0402_1005Metric"
		(layer "B.Cu")
		(at 90.377962 152.4165)
		(descr "Resistor SMD 0402")
		(tags "resistor SMD 0402")
		(property "Reference" "R237"
			(at -1.71 3.94 0)
			(layer "B.SilkS")
			(effects
				(font
					(size 0.7 0.7)
					(thickness 0.15)
				)
				(justify right bottom mirror)
			)
		)
		(property "Value" "R_10k_0402"
			(at -1.011843 -1.772047 0)
			(layer "B.Fab")
			(effects
				(font
					(size 0.7 0.7)
					(thickness 0.15)
				)
				(justify right bottom mirror)
			)
		)
		(property "Datasheet" "https://www.bourns.com/docs/product-datasheets/cr.pdf"
			(at 0 0 0)
			(layer "B.Fab")
			(hide yes)
			(effects
				(font
					(size 1.27 1.27)
					(thickness 0.15)
				)
			)
		)
		(property "MPN" "CR0402-FX-1002GLF"
			(at 0 0 0)
			(unlocked yes)
			(layer "B.Fab")
			(hide yes)
			(effects
				(font
					(size 1 1)
					(thickness 0.15)
				)
				(justify mirror)
			)
		)
		(property "Manufacturer" "Bourns"
			(at 0 0 0)
			(unlocked yes)
			(layer "B.Fab")
			(hide yes)
			(effects
				(font
					(size 1 1)
					(thickness 0.15)
				)
				(justify mirror)
			)
		)
		(property "License" "Apache-2.0"
			(at 0 0 0)
			(unlocked yes)
			(layer "B.Fab")
			(hide yes)
			(effects
				(font
					(size 1 1)
					(thickness 0.15)
				)
				(justify mirror)
			)
		)
		(property "Author" "Antmicro"
			(at 0 0 0)
			(unlocked yes)
			(layer "B.Fab")
			(hide yes)
			(effects
				(font
					(size 1 1)
					(thickness 0.15)
				)
				(justify mirror)
			)
		)
		(property "Val" "10k"
			(at 0 0 0)
			(unlocked yes)
			(layer "B.Fab")
			(hide yes)
			(effects
				(font
					(size 1 1)
					(thickness 0.15)
				)
				(justify mirror)
			)
		)
		(property "Tolerance" "1%"
			(at 0 0 0)
			(unlocked yes)
			(layer "B.Fab")
			(hide yes)
			(effects
				(font
					(size 1 1)
					(thickness 0.15)
				)
				(justify mirror)
			)
		)
		(sheetname "/Compute module/")
		(sheetfile "compute-module.kicad_sch")
		(attr smd)
		(fp_rect
			(start -0.925 0.47)
			(end 0.925 -0.47)
			(stroke
				(width 0.05)
				(type default)
			)
			(fill no)
			(layer "B.CrtYd")
		)
		(fp_rect
			(start -0.5 0.25)
			(end 0.5 -0.25)
			(stroke
				(width 0.15)
				(type solid)
			)
			(fill no)
			(layer "B.Fab")
		)
		(fp_text user "License: Apache-2.0"
			(at -0.95 -5.169 180)
			(layer "B.Fab")
			(effects
				(font
					(size 0.7 0.7)
					(thickness 0.15)
				)
				(justify left bottom mirror)
			)
		)
		(fp_text user "Author: Antmicro"
			(at -0.95 -4.169 180)
			(layer "B.Fab")
			(effects
				(font
					(size 0.7 0.7)
					(thickness 0.15)
				)
				(justify left bottom mirror)
			)
		)
		(fp_text user "${REFERENCE}"
			(at -0.95 -3.168 180)
			(layer "B.Fab")
			(effects
				(font
					(size 0.7 0.7)
					(thickness 0.15)
				)
				(justify left bottom mirror)
			)
		)
		(pad "1" smd roundrect
			(at -0.48 0)
			(size 0.59 0.64)
			(layers "B.Cu" "B.Mask" "B.Paste")
			(roundrect_rratio 0.25)
			(net 3 "GND")
			(pintype "passive")
		)
		(pad "2" smd roundrect
			(at 0.48 0)
			(size 0.59 0.64)
			(layers "B.Cu" "B.Mask" "B.Paste")
			(roundrect_rratio 0.25)
			(net 349 "Net-(U204-A0)")
			(pintype "passive")
		)
	)
)
